# S9S_MB_2U (Grand Teton) — schematic netlist excerpt (pin names and nets, part order shuffled) for the footprints in the layout excerpt that follows; sources: Cadence DE-HDL packaged netlist, KiCad conversion of 03242023_DA0F0TMBIJ0_F0T_Motherboard_J_brd_V01_OCP.brd

PC580  Q_CAPP  560UF 2.5V 20% OSCON  pkg THLF  page 285 : A = PVCCIN_CPU1 ; B = GND
C1868  Q_CAP  0.1UF 25V 10% X7R  pkg 0402  page 167 : A = P2E_MB_BMC_RX_BUF_C_DP<0> ; B = P2E_MB_BMC_RX_BUF_DP<0>
R4788  Q_RES  33.2 1% EMPTY  pkg 0402LF  page 307 : A = PWRGD_DSW_PWROK_R5 ; B = PWRGD_DSW_PWROK

(kicad_pcb
	(version 20260206)
	(generator "pcbnew")
	(generator_version "10.0")
	(general
		(thickness 1.6)
		(legacy_teardrops no)
	)
	(paper "A4")
	(title_block
		(title "03242023_DA0F0TMBIJ0_F0T_Motherboard_J_brd_V01_OCP.brd")
		(comment 1 "Grand Teton / footprints 3628-3630 of 6105")
	)
	(layers
		(0 "F.Cu" signal "TOP")
		(4 "In1.Cu" signal "GND")
		(6 "In2.Cu" signal "IN1")
		(8 "In3.Cu" signal "GND1")
		(10 "In4.Cu" signal "IN2")
		(12 "In5.Cu" signal "GND2")
		(14 "In6.Cu" signal "IN3")
		(16 "In7.Cu" signal "GND3")
		(18 "In8.Cu" signal "VCC")
		(20 "In9.Cu" signal "VCC1")
		(22 "In10.Cu" signal "GND4")
		(24 "In11.Cu" signal "IN4")
		(26 "In12.Cu" signal "GND5")
		(28 "In13.Cu" signal "IN5")
		(30 "In14.Cu" signal "GND6")
		(32 "In15.Cu" signal "IN6")
		(34 "In16.Cu" signal "GND7")
		(2 "B.Cu" signal "BOTTOM")
		(9 "F.Adhes" user "F.Adhesive")
		(11 "B.Adhes" user "B.Adhesive")
		(13 "F.Paste" user "Package Geometry/Pastemask Top")
		(15 "B.Paste" user "Package Geometry/Pastemask Bottom")
		(5 "F.SilkS" user "Ref Des/Silkscreen Top")
		(7 "B.SilkS" user "Ref Des/Silkscreen Bottom")
		(1 "F.Mask" user "Board Geometry/Soldermask Top")
		(3 "B.Mask" user "Board Geometry/Soldermask Bottom")
		(17 "Dwgs.User" user "User.Drawings")
		(19 "Cmts.User" user "User.Comments")
		(21 "Eco1.User" user "User.Eco1")
		(23 "Eco2.User" user "User.Eco2")
		(25 "Edge.Cuts" user "Board Geometry/Outline")
		(27 "Margin" user)
		(31 "F.CrtYd" user "Package Geometry/Place Bound Top")
		(29 "B.CrtYd" user "Package Geometry/Place Bound Bottom")
		(35 "F.Fab" user "Ref Des/Assembly Top")
		(33 "B.Fab" user "Ref Des/Assembly Bottom")
	)
	(footprint ""
		(layer "F.Cu")
		(at 312.42 -24.9936)
		(property "Reference" "R4788"
			(at 0 0 0)
			(layer "F.SilkS")
			(hide yes)
			(effects
				(font
					(size 1.27 1.27)
				)
			)
		)
		(property "Value" ""
			(at 0 0 0)
			(layer "F.Fab")
			(effects
				(font
					(size 1.27 1.27)
				)
			)
		)
		(duplicate_pad_numbers_are_jumpers no)
		(fp_line
			(start -0.7874 -0.4064)
			(end 0.7874 -0.4064)
			(stroke
				(width 0.1524)
				(type default)
			)
			(layer "F.SilkS")
		)
		(fp_line
			(start -0.7874 0.4064)
			(end -0.7874 -0.4064)
			(stroke
				(width 0.1524)
				(type default)
			)
			(layer "F.SilkS")
		)
		(fp_line
			(start 0.7874 -0.4064)
			(end 0.7874 0.4064)
			(stroke
				(width 0.1524)
				(type default)
			)
			(layer "F.SilkS")
		)
		(fp_line
			(start 0.7874 0.4064)
			(end -0.7874 0.4064)
			(stroke
				(width 0.1524)
				(type default)
			)
			(layer "F.SilkS")
		)
		(fp_line
			(start -0.67945 -0.305054)
			(end -0.12065 -0.305054)
			(stroke
				(width 0.1)
				(type default)
			)
			(layer "F.Fab")
		)
		(fp_line
			(start -0.67945 0.3048)
			(end -0.67945 -0.305054)
			(stroke
				(width 0.1)
				(type default)
			)
			(layer "F.Fab")
		)
		(fp_line
			(start -0.12065 -0.305054)
			(end -0.12065 -0.2794)
			(stroke
				(width 0.1)
				(type default)
			)
			(layer "F.Fab")
		)
		(fp_line
			(start -0.12065 -0.2794)
			(end 0.12065 -0.2794)
			(stroke
				(width 0.1)
				(type default)
			)
			(layer "F.Fab")
		)
		(fp_line
			(start -0.12065 0.2794)
			(end -0.12065 0.3048)
			(stroke
				(width 0.1)
				(type default)
			)
			(layer "F.Fab")
		)
		(fp_line
			(start -0.12065 0.3048)
			(end -0.67945 0.3048)
			(stroke
				(width 0.1)
				(type default)
			)
			(layer "F.Fab")
		)
		(fp_line
			(start 0.120396 0.2794)
			(end -0.12065 0.2794)
			(stroke
				(width 0.1)
				(type default)
			)
			(layer "F.Fab")
		)
		(fp_line
			(start 0.120396 0.3048)
			(end 0.120396 0.2794)
			(stroke
				(width 0.1)
				(type default)
			)
			(layer "F.Fab")
		)
		(fp_line
			(start 0.12065 -0.3048)
			(end 0.67945 -0.3048)
			(stroke
				(width 0.1)
				(type default)
			)
			(layer "F.Fab")
		)
		(fp_line
			(start 0.12065 -0.2794)
			(end 0.12065 -0.3048)
			(stroke
				(width 0.1)
				(type default)
			)
			(layer "F.Fab")
		)
		(fp_line
			(start 0.67945 -0.3048)
			(end 0.67945 0.3048)
			(stroke
				(width 0.1)
				(type default)
			)
			(layer "F.Fab")
		)
		(fp_line
			(start 0.67945 0.3048)
			(end 0.120396 0.3048)
			(stroke
				(width 0.1)
				(type default)
			)
			(layer "F.Fab")
		)
		(pad "1" smd circle
			(at -0.40005 0)
			(size 0 0)
			(layers "F.Cu" "F.Mask" "F.Paste")
			(net "PWRGD_DSW_PWROK_R5")
		)
		(pad "2" smd circle
			(at 0.40005 0)
			(size 0 0)
			(layers "F.Cu" "F.Mask" "F.Paste")
			(net "PWRGD_DSW_PWROK")
		)
	)
	(footprint ""
		(layer "F.Cu")
		(at 23.767034 -385.778248 -90)
		(property "Reference" "C1868"
			(at 0 0 270)
			(layer "F.SilkS")
			(hide yes)
			(effects
				(font
					(size 1.27 1.27)
				)
			)
		)
		(property "Value" ""
			(at 0 0 270)
			(layer "F.Fab")
			(effects
				(font
					(size 1.27 1.27)
				)
			)
		)
		(duplicate_pad_numbers_are_jumpers no)
		(fp_line
			(start -0.002032 0.4064)
			(end -0.7874 0.4064)
			(stroke
				(width 0.1524)
				(type default)
			)
			(layer "F.SilkS")
		)
		(fp_line
			(start -0.7874 -0.4064)
			(end 0.7874 -0.4064)
			(stroke
				(width 0.1524)
				(type default)
			)
			(layer "F.SilkS")
		)
		(fp_line
			(start 0.7874 -0.4064)
			(end 0.7874 0.4064)
			(stroke
				(width 0.1524)
				(type default)
			)
			(layer "F.SilkS")
		)
		(fp_line
			(start -0.6858 0.3048)
			(end -0.6858 -0.3048)
			(stroke
				(width 0.1)
				(type default)
			)
			(layer "F.Fab")
		)
		(fp_line
			(start -0.1016 0.3048)
			(end -0.6858 0.3048)
			(stroke
				(width 0.1)
				(type default)
			)
			(layer "F.Fab")
		)
		(fp_line
			(start 0.1016 0.3048)
			(end 0.1016 0.2794)
			(stroke
				(width 0.1)
				(type default)
			)
			(layer "F.Fab")
		)
		(fp_line
			(start 0.6858 0.3048)
			(end 0.1016 0.3048)
			(stroke
				(width 0.1)
				(type default)
			)
			(layer "F.Fab")
		)
		(fp_line
			(start -0.1016 0.2794)
			(end -0.1016 0.3048)
			(stroke
				(width 0.1)
				(type default)
			)
			(layer "F.Fab")
		)
		(fp_line
			(start 0.1016 0.2794)
			(end -0.1016 0.2794)
			(stroke
				(width 0.1)
				(type default)
			)
			(layer "F.Fab")
		)
		(fp_line
			(start -0.1016 -0.2794)
			(end 0.1016 -0.2794)
			(stroke
				(width 0.1)
				(type default)
			)
			(layer "F.Fab")
		)
		(fp_line
			(start 0.1016 -0.2794)
			(end 0.1016 -0.3048)
			(stroke
				(width 0.1)
				(type default)
			)
			(layer "F.Fab")
		)
		(fp_line
			(start -0.6858 -0.3048)
			(end -0.1016 -0.3048)
			(stroke
				(width 0.1)
				(type default)
			)
			(layer "F.Fab")
		)
		(fp_line
			(start -0.1016 -0.3048)
			(end -0.1016 -0.2794)
			(stroke
				(width 0.1)
				(type default)
			)
			(layer "F.Fab")
		)
		(fp_line
			(start 0.1016 -0.3048)
			(end 0.6858 -0.3048)
			(stroke
				(width 0.1)
				(type default)
			)
			(layer "F.Fab")
		)
		(fp_line
			(start 0.6858 -0.3048)
			(end 0.6858 0.3048)
			(stroke
				(width 0.1)
				(type default)
			)
			(layer "F.Fab")
		)
		(pad "1" smd rect
			(at -0.40005 0 90)
			(size 0.4572 0.508)
			(layers "F.Cu" "F.Mask" "F.Paste")
			(net "P2E_MB_BMC_RX_BUF_C_DP<0>")
		)
		(pad "2" smd rect
			(at 0.40005 0 90)
			(size 0.4572 0.508)
			(layers "F.Cu" "F.Mask" "F.Paste")
			(net "P2E_MB_BMC_RX_BUF_DP<0>")
		)
	)
	(footprint ""
		(layer "F.Cu")
		(at 98.525838 -315.66739 90)
		(property "Reference" "PC580"
			(at 0 0 90)
			(layer "F.SilkS")
			(hide yes)
			(effects
				(font
					(size 1.27 1.27)
				)
			)
		)
		(property "Value" ""
			(at 0 0 90)
			(layer "F.Fab")
			(effects
				(font
					(size 1.27 1.27)
				)
			)
		)
		(duplicate_pad_numbers_are_jumpers no)
		(fp_line
			(start 2.750058 0.999998)
			(end -2.750058 0.999998)
			(stroke
				(width 0.1524)
				(type default)
			)
			(layer "F.SilkS")
		)
		(fp_circle
			(center 0 0.999998)
			(end 0 3.750056)
			(stroke
				(width 0.1524)
				(type default)
			)
			(fill no)
			(layer "F.SilkS")
		)
		(fp_poly
			(pts
				(arc
					(start 2.750058 0.999998)
					(mid 0 3.750056)
					(end -2.750058 0.999998)
				)
			)
			(stroke
				(width 0)
				(type default)
			)
			(fill yes)
			(layer "F.SilkS")
		)
		(fp_circle
			(center 0 0.999998)
			(end 0 3.750056)
			(stroke
				(width 0.1)
				(type default)
			)
			(fill no)
			(layer "F.Fab")
		)
		(pad "1" thru_hole rect
			(at 0 0 90)
			(size 1.5748 1.5748)
			(drill 1.0668)
			(layers "*.Cu" "*.Mask")
			(remove_unused_layers no)
			(net "PVCCIN_CPU1")
			(clearance 0)
			(padstack
				(mode front_inner_back)
				(layer "Inner"
					(shape circle)
					(size 1.5748 1.5748)
					(clearance 0)
				)
				(layer "B.Cu"
					(shape rect)
					(size 1.5748 1.5748)
					(clearance 0)
				)
			)
		)
		(pad "2" thru_hole circle
			(at 0 1.999996 90)
			(size 1.5748 1.5748)
			(drill 1.0668)
			(layers "*.Cu" "*.Mask")
			(remove_unused_layers no)
			(net "GND")
			(clearance 0)
		)
	)
)
